(kicad_pcb
	(version 20260206)
	(generator "pcbnew")
	(generator_version "10.0")
	(general
		(thickness 1.21888)
		(legacy_teardrops no)
	)
	(paper "A4")
	(title_block
		(title "timecard-v9 — TimeCard-DC-V9_EXP.PcbDoc")
		(comment 1 "Time Appliance Project (Time Card) / footprints 354-363 of 402")
	)
	(layers
		(0 "F.Cu" signal "TOP")
		(4 "In1.Cu" signal "SGND")
		(6 "In2.Cu" signal "IN1")
		(8 "In3.Cu" signal "IN2")
		(10 "In4.Cu" signal "SGND1")
		(2 "B.Cu" signal "BOTTOM")
		(9 "F.Adhes" user "F.Adhesive")
		(11 "B.Adhes" user "B.Adhesive")
		(13 "F.Paste" user "Top Paste")
		(15 "B.Paste" user "Bottom Paste")
		(5 "F.SilkS" user "Top Overlay")
		(7 "B.SilkS" user "Bottom Overlay")
		(1 "F.Mask" user "Top Solder")
		(3 "B.Mask" user "Bottom Solder")
		(17 "Dwgs.User" user "User.Drawings")
		(19 "Cmts.User" user "User.Comments")
		(21 "Eco1.User" user "User.Eco1")
		(23 "Eco2.User" user "User.Eco2")
		(25 "Edge.Cuts" user)
		(27 "Margin" user)
		(31 "F.CrtYd" user "Top Courtyard")
		(29 "B.CrtYd" user "Bottom Courtyard")
		(35 "F.Fab" user "Top Component Center")
		(33 "B.Fab" user "Bottom Component Center")
	)
	(footprint "Vault:FP-CL829-IPC_C"
		(layer "B.Cu")
		(at 228.14659 132.0162)
		(property "Reference" "C90"
			(at -0.25359 1.526931 0)
			(unlocked yes)
			(layer "B.SilkS")
			(effects
				(font
					(size 0.762 0.762)
					(thickness 0.2286)
				)
				(justify mirror)
			)
		)
		(property "Value" "4.7uF_16V_0402"
			(at -2.440151 -9.864605 270)
			(unlocked yes)
			(layer "B.SilkS")
			(hide yes)
			(effects
				(font
					(size 0.762 0.762)
					(thickness 0.2286)
				)
				(justify mirror)
			)
		)
		(sheetname "09-USBUart_PPSMUX_UARTMUX")
		(sheetfile "09-USBUart_PPSMUX_UARTMUX.kicad_sch")
		(duplicate_pad_numbers_are_jumpers no)
		(fp_line
			(start -0.63623 -0.675)
			(end 0.63624 -0.675)
			(stroke
				(width 0.2)
				(type solid)
			)
			(layer "B.SilkS")
		)
		(fp_line
			(start -0.63623 0.675)
			(end 0.63624 0.675)
			(stroke
				(width 0.2)
				(type solid)
			)
			(layer "B.SilkS")
		)
		(fp_line
			(start -0.73623 -0.375)
			(end 0.73624 -0.375)
			(stroke
				(width 0.2)
				(type solid)
			)
			(layer "B.CrtYd")
		)
		(fp_line
			(start -0.73623 0.375)
			(end -0.73623 -0.375)
			(stroke
				(width 0.2)
				(type solid)
			)
			(layer "B.CrtYd")
		)
		(fp_line
			(start -0.73623 0.375)
			(end 0.73624 0.375)
			(stroke
				(width 0.2)
				(type solid)
			)
			(layer "B.CrtYd")
		)
		(fp_line
			(start 0.73624 0.375)
			(end 0.73624 -0.375)
			(stroke
				(width 0.2)
				(type solid)
			)
			(layer "B.CrtYd")
		)
		(fp_line
			(start -0.73623 -0.375)
			(end 0.73624 -0.375)
			(stroke
				(width 0.2)
				(type solid)
			)
			(layer "B.Fab")
		)
		(fp_line
			(start -0.73623 0.375)
			(end -0.73623 -0.375)
			(stroke
				(width 0.2)
				(type solid)
			)
			(layer "B.Fab")
		)
		(fp_line
			(start -0.73623 0.375)
			(end 0.73624 0.375)
			(stroke
				(width 0.2)
				(type solid)
			)
			(layer "B.Fab")
		)
		(fp_line
			(start -0.5 0)
			(end 0.5 0)
			(stroke
				(width 0.1)
				(type solid)
			)
			(layer "B.Fab")
		)
		(fp_line
			(start -0.5 0)
			(end 0.5 0)
			(stroke
				(width 0.1)
				(type solid)
			)
			(layer "B.Fab")
		)
		(fp_line
			(start 0 0.5)
			(end 0 -0.5)
			(stroke
				(width 0.1)
				(type solid)
			)
			(layer "B.Fab")
		)
		(fp_line
			(start 0 0.5)
			(end 0 -0.5)
			(stroke
				(width 0.1)
				(type solid)
			)
			(layer "B.Fab")
		)
		(fp_line
			(start 0.73624 0.375)
			(end 0.73624 -0.375)
			(stroke
				(width 0.2)
				(type solid)
			)
			(layer "B.Fab")
		)
		(fp_text user "${REFERENCE}"
			(at 0 -0.28424 180)
			(unlocked yes)
			(layer "B.Fab")
			(effects
				(font
					(face "Arial")
					(size 0.63 0.63)
					(thickness 0.1)
				)
				(justify left bottom mirror)
			)
		)
		(pad "1" smd rect
			(at -0.37856 0)
			(size 0.51535 0.47247)
			(layers "B.Cu" "B.Mask" "B.Paste")
			(net "FTDI_VBUS")
			(solder_mask_margin 0)
			(solder_paste_margin 0)
		)
		(pad "2" smd rect
			(at 0.37857 0)
			(size 0.51535 0.47247)
			(layers "B.Cu" "B.Mask" "B.Paste")
			(net "GND")
			(solder_mask_margin 0)
			(solder_paste_margin 0)
		)
	)
	(footprint "Vault:RESC1005X40X25LL05T10"
		(layer "B.Cu")
		(at 221.91312 95.8124 -90)
		(property "Reference" "R141"
			(at -0.0994 -1.081549 270)
			(unlocked yes)
			(layer "B.SilkS")
			(effects
				(font
					(size 0.762 0.762)
					(thickness 0.2032)
				)
				(justify mirror)
			)
		)
		(property "Value" "10K_1%_0402"
			(at -2.579871 -8.036515 180)
			(unlocked yes)
			(layer "B.SilkS")
			(hide yes)
			(effects
				(font
					(size 0.762 0.762)
					(thickness 0.2032)
				)
				(justify mirror)
			)
		)
		(sheetname "08-DIPSwitches_I2C")
		(sheetfile "08-DIPSwitches_I2C.kicad_sch")
		(duplicate_pad_numbers_are_jumpers no)
		(pad "1" smd rect
			(at -0.375 0 180)
			(size 0.45 0.5)
			(layers "B.Cu" "B.Mask" "B.Paste")
			(net "+3.3V")
		)
		(pad "2" smd rect
			(at 0.375 0 180)
			(size 0.45 0.5)
			(layers "B.Cu" "B.Mask" "B.Paste")
			(net "DIP_SW_GPS1_SEL")
		)
	)
	(footprint "Vault:FP-0402-L_1_0_1-W_0_5_0_1-IPC_C"
		(layer "B.Cu")
		(at 123.8966 55.8662 90)
		(property "Reference" "C97"
			(at 2.3468 -0.148069 90)
			(unlocked yes)
			(layer "B.SilkS")
			(effects
				(font
					(size 0.762 0.762)
					(thickness 0.2032)
				)
				(justify mirror)
			)
		)
		(property "Value" "0.1uF_25V_0402"
			(at -2.465551 -9.813815 0)
			(unlocked yes)
			(layer "B.SilkS")
			(hide yes)
			(effects
				(font
					(size 0.762 0.762)
					(thickness 0.2032)
				)
				(justify mirror)
			)
		)
		(sheetname "10-M2_GPS")
		(sheetfile "10-M2_GPS.kicad_sch")
		(duplicate_pad_numbers_are_jumpers no)
		(fp_line
			(start -0.65607 -0.7)
			(end 0.65607 -0.7)
			(stroke
				(width 0.2)
				(type solid)
			)
			(layer "B.SilkS")
		)
		(fp_line
			(start -0.65607 0.7)
			(end 0.65607 0.7)
			(stroke
				(width 0.2)
				(type solid)
			)
			(layer "B.SilkS")
		)
		(fp_line
			(start 0.75607 -0.4)
			(end 0.75607 0.4)
			(stroke
				(width 0.2)
				(type solid)
			)
			(layer "B.CrtYd")
		)
		(fp_line
			(start -0.75607 -0.4)
			(end 0.75607 -0.4)
			(stroke
				(width 0.2)
				(type solid)
			)
			(layer "B.CrtYd")
		)
		(fp_line
			(start -0.75607 -0.4)
			(end -0.75607 0.4)
			(stroke
				(width 0.2)
				(type solid)
			)
			(layer "B.CrtYd")
		)
		(fp_line
			(start -0.75607 0.4)
			(end 0.75607 0.4)
			(stroke
				(width 0.2)
				(type solid)
			)
			(layer "B.CrtYd")
		)
		(fp_line
			(start 0 -0.5)
			(end 0 0.5)
			(stroke
				(width 0.1)
				(type solid)
			)
			(layer "B.Fab")
		)
		(fp_line
			(start 0.75607 -0.4)
			(end 0.75607 0.4)
			(stroke
				(width 0.2)
				(type solid)
			)
			(layer "B.Fab")
		)
		(fp_line
			(start -0.75607 -0.4)
			(end 0.75607 -0.4)
			(stroke
				(width 0.2)
				(type solid)
			)
			(layer "B.Fab")
		)
		(fp_line
			(start -0.75607 -0.4)
			(end -0.75607 0.4)
			(stroke
				(width 0.2)
				(type solid)
			)
			(layer "B.Fab")
		)
		(fp_line
			(start -0.5 0)
			(end 0.5 0)
			(stroke
				(width 0.1)
				(type solid)
			)
			(layer "B.Fab")
		)
		(fp_line
			(start -0.75607 0.4)
			(end 0.75607 0.4)
			(stroke
				(width 0.2)
				(type solid)
			)
			(layer "B.Fab")
		)
		(fp_text user "${REFERENCE}"
			(at -0.00002 -0.09602 270)
			(unlocked yes)
			(layer "B.Fab")
			(effects
				(font
					(face "Arial")
					(size 0.63 0.63)
					(thickness 0.1)
				)
				(justify left bottom mirror)
			)
		)
		(pad "1" smd rect
			(at -0.36554 0 90)
			(size 0.58106 0.51213)
			(layers "B.Cu" "B.Mask" "B.Paste")
			(net "+3.3V")
			(solder_mask_margin 0)
			(solder_paste_margin 0)
		)
		(pad "2" smd rect
			(at 0.36554 0 90)
			(size 0.58106 0.51213)
			(layers "B.Cu" "B.Mask" "B.Paste")
			(net "GND")
			(solder_mask_margin 0)
			(solder_paste_margin 0)
		)
	)
	(footprint "Vault:FP-0402-L_1_0_0_05-W_0_5-IPC_C"
		(layer "B.Cu")
		(at 110.58072 86.6662 180)
		(property "Reference" "C65"
			(at 2.48772 -0.094851 0)
			(unlocked yes)
			(layer "B.SilkS")
			(effects
				(font
					(size 0.762 0.762)
					(thickness 0.2286)
				)
				(justify mirror)
			)
		)
		(property "Value" "1uF_0402"
			(at -2.795791 -1.459875 90)
			(unlocked yes)
			(layer "B.SilkS")
			(hide yes)
			(effects
				(font
					(size 0.762 0.762)
					(thickness 0.2286)
				)
				(justify mirror)
			)
		)
		(sheetname "05-GPS_IMU_SENSORS")
		(sheetfile "05-GPS_IMU_SENSORS.kicad_sch")
		(duplicate_pad_numbers_are_jumpers no)
		(fp_line
			(start 0.63623 0.675)
			(end -0.63624 0.675)
			(stroke
				(width 0.2)
				(type solid)
			)
			(layer "B.SilkS")
		)
		(fp_line
			(start 0.63623 -0.675)
			(end -0.63624 -0.675)
			(stroke
				(width 0.2)
				(type solid)
			)
			(layer "B.SilkS")
		)
		(fp_line
			(start 0.73623 0.375)
			(end -0.73624 0.375)
			(stroke
				(width 0.2)
				(type solid)
			)
			(layer "B.CrtYd")
		)
		(fp_line
			(start 0.73623 -0.375)
			(end 0.73623 0.375)
			(stroke
				(width 0.2)
				(type solid)
			)
			(layer "B.CrtYd")
		)
		(fp_line
			(start 0.73623 -0.375)
			(end -0.73624 -0.375)
			(stroke
				(width 0.2)
				(type solid)
			)
			(layer "B.CrtYd")
		)
		(fp_line
			(start -0.73624 -0.375)
			(end -0.73624 0.375)
			(stroke
				(width 0.2)
				(type solid)
			)
			(layer "B.CrtYd")
		)
		(fp_line
			(start 0.73623 0.375)
			(end -0.73624 0.375)
			(stroke
				(width 0.2)
				(type solid)
			)
			(layer "B.Fab")
		)
		(fp_line
			(start 0.73623 -0.375)
			(end 0.73623 0.375)
			(stroke
				(width 0.2)
				(type solid)
			)
			(layer "B.Fab")
		)
		(fp_line
			(start 0.73623 -0.375)
			(end -0.73624 -0.375)
			(stroke
				(width 0.2)
				(type solid)
			)
			(layer "B.Fab")
		)
		(fp_line
			(start 0.5 0)
			(end -0.5 0)
			(stroke
				(width 0.1)
				(type solid)
			)
			(layer "B.Fab")
		)
		(fp_line
			(start 0 -0.5)
			(end 0 0.5)
			(stroke
				(width 0.1)
				(type solid)
			)
			(layer "B.Fab")
		)
		(fp_line
			(start -0.73624 -0.375)
			(end -0.73624 0.375)
			(stroke
				(width 0.2)
				(type solid)
			)
			(layer "B.Fab")
		)
		(fp_text user "${REFERENCE}"
			(at -0.00001 -0.09602 360)
			(unlocked yes)
			(layer "B.Fab")
			(effects
				(font
					(face "Arial")
					(size 0.63 0.63)
					(thickness 0.1)
				)
				(justify left bottom mirror)
			)
		)
		(pad "1" smd rect
			(at -0.37856 0 180)
			(size 0.51535 0.47247)
			(layers "B.Cu" "B.Mask" "B.Paste")
			(net "NetC65_1")
			(solder_mask_margin 0)
			(solder_paste_margin 0)
		)
		(pad "2" smd rect
			(at 0.37856 0 180)
			(size 0.51535 0.47247)
			(layers "B.Cu" "B.Mask" "B.Paste")
			(net "GND")
			(solder_mask_margin 0)
			(solder_paste_margin 0)
		)
	)
	(footprint "Vault:RESC1005X40X25LL05T05"
		(layer "B.Cu")
		(at 112.48072 87.8662 180)
		(property "Reference" "R54"
			(at 0.13052 -7.123069 180)
			(unlocked yes)
			(layer "B.SilkS")
			(effects
				(font
					(size 0.762 0.762)
					(thickness 0.2286)
				)
				(justify mirror)
			)
		)
		(property "Value" "0_1%_0402"
			(at -2.579881 -6.66536 90)
			(unlocked yes)
			(layer "B.SilkS")
			(hide yes)
			(effects
				(font
					(size 0.762 0.762)
					(thickness 0.2286)
				)
				(justify mirror)
			)
		)
		(sheetname "05-GPS_IMU_SENSORS")
		(sheetfile "05-GPS_IMU_SENSORS.kicad_sch")
		(duplicate_pad_numbers_are_jumpers no)
		(pad "1" smd rect
			(at -0.4 0 90)
			(size 0.45 0.45)
			(layers "B.Cu" "B.Mask" "B.Paste")
			(net "PCIE_PERST")
		)
		(pad "2" smd rect
			(at 0.4 0 90)
			(size 0.45 0.45)
			(layers "B.Cu" "B.Mask" "B.Paste")
			(net "NetR52_1")
		)
	)
	(footprint "Capacitors:CAPC1005X06N"
		(layer "B.Cu")
		(at 137.3846 151.7886 90)
		(property "Reference" "C51"
			(at 2.41349 0.148145 270)
			(unlocked yes)
			(layer "B.SilkS")
			(effects
				(font
					(size 0.762 0.762)
					(thickness 0.2286)
				)
				(justify left bottom mirror)
			)
		)
		(property "Value" "CAP_0402_0.1UF_50V"
			(at -3.382645 0.2921 0)
			(unlocked yes)
			(layer "B.SilkS")
			(hide yes)
			(effects
				(font
					(size 0.762 0.762)
					(thickness 0.2286)
				)
				(justify left bottom mirror)
			)
		)
		(sheetname "04-PCIe_JTAG")
		(sheetfile "04-PCIe_JTAG.kicad_sch")
		(duplicate_pad_numbers_are_jumpers no)
		(pad "1" smd rect
			(at -0.43 0)
			(size 0.64 0.68)
			(layers "B.Cu" "B.Mask" "B.Paste")
			(net "NetC51_1")
		)
		(pad "2" smd rect
			(at 0.43 0)
			(size 0.64 0.68)
			(layers "B.Cu" "B.Mask" "B.Paste")
			(net "PCIE_TX2_N")
		)
	)
	(footprint "Vault:FP-0402-L_1_0_1-W_0_5_0_1-IPC_C"
		(layer "B.Cu")
		(at 219.66155 125.59915 90)
		(property "Reference" "C112"
			(at 2.02895 0.186971 90)
			(unlocked yes)
			(layer "B.SilkS")
			(effects
				(font
					(size 0.762 0.762)
					(thickness 0.254)
				)
				(justify mirror)
			)
		)
		(property "Value" "0.1uF_25V_0402"
			(at -2.465561 -9.864615 0)
			(unlocked yes)
			(layer "B.SilkS")
			(hide yes)
			(effects
				(font
					(size 0.762 0.762)
					(thickness 0.254)
				)
				(justify mirror)
			)
		)
		(sheetname "09-USBUart_PPSMUX_UARTMUX")
		(sheetfile "09-USBUart_PPSMUX_UARTMUX.kicad_sch")
		(duplicate_pad_numbers_are_jumpers no)
		(fp_line
			(start -0.65607 -0.7)
			(end 0.65606 -0.7)
			(stroke
				(width 0.2)
				(type solid)
			)
			(layer "B.SilkS")
		)
		(fp_line
			(start -0.65607 0.7)
			(end 0.65606 0.7)
			(stroke
				(width 0.2)
				(type solid)
			)
			(layer "B.SilkS")
		)
		(fp_line
			(start 0.75606 -0.4)
			(end 0.75606 0.4)
			(stroke
				(width 0.2)
				(type solid)
			)
			(layer "B.CrtYd")
		)
		(fp_line
			(start -0.75607 -0.4)
			(end 0.75606 -0.4)
			(stroke
				(width 0.2)
				(type solid)
			)
			(layer "B.CrtYd")
		)
		(fp_line
			(start -0.75607 -0.4)
			(end -0.75607 0.4)
			(stroke
				(width 0.2)
				(type solid)
			)
			(layer "B.CrtYd")
		)
		(fp_line
			(start -0.75607 0.4)
			(end 0.75606 0.4)
			(stroke
				(width 0.2)
				(type solid)
			)
			(layer "B.CrtYd")
		)
		(fp_line
			(start 0 -0.5)
			(end 0 0.5)
			(stroke
				(width 0.1)
				(type solid)
			)
			(layer "B.Fab")
		)
		(fp_line
			(start 0.75606 -0.4)
			(end 0.75606 0.4)
			(stroke
				(width 0.2)
				(type solid)
			)
			(layer "B.Fab")
		)
		(fp_line
			(start -0.75607 -0.4)
			(end 0.75606 -0.4)
			(stroke
				(width 0.2)
				(type solid)
			)
			(layer "B.Fab")
		)
		(fp_line
			(start -0.75607 -0.4)
			(end -0.75607 0.4)
			(stroke
				(width 0.2)
				(type solid)
			)
			(layer "B.Fab")
		)
		(fp_line
			(start -0.5 0)
			(end 0.49999 0)
			(stroke
				(width 0.1)
				(type solid)
			)
			(layer "B.Fab")
		)
		(fp_line
			(start -0.75607 0.4)
			(end 0.75606 0.4)
			(stroke
				(width 0.2)
				(type solid)
			)
			(layer "B.Fab")
		)
		(fp_text user "${REFERENCE}"
			(at -0.00002 -0.09602 270)
			(unlocked yes)
			(layer "B.Fab")
			(effects
				(font
					(face "Arial")
					(size 0.63 0.63)
					(thickness 0.1)
				)
				(justify left bottom mirror)
			)
		)
		(pad "1" smd rect
			(at -0.36554 0 90)
			(size 0.58106 0.51213)
			(layers "B.Cu" "B.Mask" "B.Paste")
			(net "FTDI_P3V3")
			(solder_mask_margin 0)
			(solder_paste_margin 0)
		)
		(pad "2" smd rect
			(at 0.36553 0 90)
			(size 0.58106 0.51213)
			(layers "B.Cu" "B.Mask" "B.Paste")
			(net "GND")
			(solder_mask_margin 0)
			(solder_paste_margin 0)
		)
	)
	(footprint "Vault:RESC1005X40X25NL10T10"
		(layer "B.Cu")
		(at 85.1216 55.0162)
		(property "Reference" "R60"
			(at 0.4786 1.123069 180)
			(unlocked yes)
			(layer "B.SilkS")
			(effects
				(font
					(size 0.762 0.762)
					(thickness 0.2286)
				)
				(justify mirror)
			)
		)
		(property "Value" "10K_1%_0402"
			(at -2.732271 -9.407665 270)
			(unlocked yes)
			(layer "B.SilkS")
			(hide yes)
			(effects
				(font
					(size 0.762 0.762)
					(thickness 0.2286)
				)
				(justify mirror)
			)
		)
		(sheetname "03-POWER")
		(sheetfile "03-POWER.kicad_sch")
		(duplicate_pad_numbers_are_jumpers no)
		(pad "1" smd rect
			(at -0.425 0 270)
			(size 0.6 0.65)
			(layers "B.Cu" "B.Mask" "B.Paste")
			(net "GND")
		)
		(pad "2" smd rect
			(at 0.425 0 270)
			(size 0.6 0.65)
			(layers "B.Cu" "B.Mask" "B.Paste")
			(net "NetR6_2")
		)
	)
	(footprint "Vault:RESC1005X40X25LL05T05"
		(layer "B.Cu")
		(at 112.25573 88.6912 180)
		(property "Reference" "R50"
			(at -0.09447 -7.498069 180)
			(unlocked yes)
			(layer "B.SilkS")
			(effects
				(font
					(size 0.762 0.762)
					(thickness 0.2286)
				)
				(justify mirror)
			)
		)
		(property "Value" "4.7K_0402"
			(at -3.024391 -2.374045 90)
			(unlocked yes)
			(layer "B.SilkS")
			(hide yes)
			(effects
				(font
					(size 0.762 0.762)
					(thickness 0.2286)
				)
				(justify mirror)
			)
		)
		(sheetname "05-GPS_IMU_SENSORS")
		(sheetfile "05-GPS_IMU_SENSORS.kicad_sch")
		(duplicate_pad_numbers_are_jumpers no)
		(pad "1" smd rect
			(at -0.39999 0 90)
			(size 0.45 0.45)
			(layers "B.Cu" "B.Mask" "B.Paste")
			(net "BNO_P3V3")
		)
		(pad "2" smd rect
			(at 0.40001 0 90)
			(size 0.45 0.45)
			(layers "B.Cu" "B.Mask" "B.Paste")
			(net "BNO_INT")
		)
	)
	(footprint "Vault:FP-0402-L_1_0_1-W_0_5_0_1-IPC_C"
		(layer "B.Cu")
		(at 215.8716 121.4405 180)
		(property "Reference" "C104"
			(at 1.0408 1.556359 0)
			(unlocked yes)
			(layer "B.SilkS")
			(effects
				(font
					(size 0.762 0.762)
					(thickness 0.2032)
				)
				(justify mirror)
			)
		)
		(property "Value" "0.1uF_25V_0402"
			(at -2.465551 -9.813805 90)
			(unlocked yes)
			(layer "B.SilkS")
			(hide yes)
			(effects
				(font
					(size 0.762 0.762)
					(thickness 0.2032)
				)
				(justify mirror)
			)
		)
		(sheetname "10-M2_GPS")
		(sheetfile "10-M2_GPS.kicad_sch")
		(duplicate_pad_numbers_are_jumpers no)
		(fp_line
			(start 0.65607 0.7)
			(end -0.65607 0.7)
			(stroke
				(width 0.2)
				(type solid)
			)
			(layer "B.SilkS")
		)
		(fp_line
			(start 0.65607 -0.7)
			(end -0.65607 -0.7)
			(stroke
				(width 0.2)
				(type solid)
			)
			(layer "B.SilkS")
		)
		(fp_line
			(start 0.75607 0.4)
			(end -0.75607 0.4)
			(stroke
				(width 0.2)
				(type solid)
			)
			(layer "B.CrtYd")
		)
		(fp_line
			(start 0.75607 -0.4)
			(end 0.75607 0.4)
			(stroke
				(width 0.2)
				(type solid)
			)
			(layer "B.CrtYd")
		)
		(fp_line
			(start 0.75607 -0.4)
			(end -0.75607 -0.4)
			(stroke
				(width 0.2)
				(type solid)
			)
			(layer "B.CrtYd")
		)
		(fp_line
			(start -0.75607 -0.4)
			(end -0.75607 0.4)
			(stroke
				(width 0.2)
				(type solid)
			)
			(layer "B.CrtYd")
		)
		(fp_line
			(start 0.75607 0.4)
			(end -0.75607 0.4)
			(stroke
				(width 0.2)
				(type solid)
			)
			(layer "B.Fab")
		)
		(fp_line
			(start 0.75607 -0.4)
			(end 0.75607 0.4)
			(stroke
				(width 0.2)
				(type solid)
			)
			(layer "B.Fab")
		)
		(fp_line
			(start 0.75607 -0.4)
			(end -0.75607 -0.4)
			(stroke
				(width 0.2)
				(type solid)
			)
			(layer "B.Fab")
		)
		(fp_line
			(start 0.5 0)
			(end -0.5 0)
			(stroke
				(width 0.1)
				(type solid)
			)
			(layer "B.Fab")
		)
		(fp_line
			(start 0 -0.5)
			(end 0 0.5)
			(stroke
				(width 0.1)
				(type solid)
			)
			(layer "B.Fab")
		)
		(fp_line
			(start -0.75607 -0.4)
			(end -0.75607 0.4)
			(stroke
				(width 0.2)
				(type solid)
			)
			(layer "B.Fab")
		)
		(fp_text user "${REFERENCE}"
			(at -0.00001 -0.09601 360)
			(unlocked yes)
			(layer "B.Fab")
			(effects
				(font
					(face "Arial")
					(size 0.63 0.63)
					(thickness 0.1)
				)
				(justify left bottom mirror)
			)
		)
		(pad "1" smd rect
			(at -0.36554 0 180)
			(size 0.58106 0.51213)
			(layers "B.Cu" "B.Mask" "B.Paste")
			(net "GNSS2_P3V3")
			(solder_mask_margin 0)
			(solder_paste_margin 0)
		)
		(pad "2" smd rect
			(at 0.36554 0 180)
			(size 0.58106 0.51213)
			(layers "B.Cu" "B.Mask" "B.Paste")
			(net "GND")
			(solder_mask_margin 0)
			(solder_paste_margin 0)
		)
	)
)
